# S9S_MB_2U (Grand Teton) — schematic netlist excerpt (pin names and nets, part order shuffled) for the footprints in the layout excerpt that follows; sources: Cadence DE-HDL packaged netlist, KiCad conversion of 03242023_DA0F0TMBIJ0_F0T_Motherboard_J_brd_V01_OCP.brd

J16  SCONN288_ADR50017P087CC  SCONN288_ADR50017-P087CC IO  pkg DDR288S_1-1VXB  page 97
  VIN_BULK0  = P12V_S3_AUX_CPU0_NVDIMM
  RFU0  = TP_CHH_CPU0_DIMM2_FRU_0
  VIN_MGMT  = P3V3_AUX
  HSCL  = I3C_SPD_DDREFGH_CPU0_LVC1_SCL_7
  HSDA  = I3C_SPD_DDREFGH_CPU0_LVC1_SDA
  VSS0  = GND
  DQ0_A  = M_H_CPU0_SA_DQ<0>
  VSS1  = GND
  DQ1_A  = M_H_CPU0_SA_DQ<1>
  VSS2  = GND
  DQS0_A_T  = M_H_CPU0_SA_DQS_DP<0>
  DQS0_A_C  = M_H_CPU0_SA_DQS_DN<0>
  VSS3  = GND
  DQ4_A  = M_H_CPU0_SA_DQ<4>
  VSS4  = GND
  DQ5_A  = M_H_CPU0_SA_DQ<5>
  VSS5  = GND
  DQ8_A  = M_H_CPU0_SA_DQ<8>
  VSS6  = GND
  DQ9_A  = M_H_CPU0_SA_DQ<9>
  VSS7  = GND
  DQS1_A_T  = M_H_CPU0_SA_DQS_DP<1>
  DQS1_A_C  = M_H_CPU0_SA_DQS_DN<1>
  VSS8  = GND
  DQ12_A  = M_H_CPU0_SA_DQ<12>
  VSS9  = GND
  DQ13_A  = M_H_CPU0_SA_DQ<13>
  VSS10  = GND
  DQ16_A  = M_H_CPU0_SA_DQ<16>
  VSS11  = GND
  DQ17_A  = M_H_CPU0_SA_DQ<17>
  VSS12  = GND
  DQS2_A_T  = M_H_CPU0_SA_DQS_DP<2>
  DQS2_A_C  = M_H_CPU0_SA_DQS_DN<2>
  VSS13  = GND
  DQ20_A  = M_H_CPU0_SA_DQ<20>
  VSS14  = GND
  DQ21_A  = M_H_CPU0_SA_DQ<21>
  VSS15  = GND
  DQ24_A  = M_H_CPU0_SA_DQ<24>
  VSS16  = GND
  DQ25_A  = M_H_CPU0_SA_DQ<25>
  VSS17  = GND
  DQS3_A_T  = M_H_CPU0_SA_DQS_DP<3>
  DQS3_A_C  = M_H_CPU0_SA_DQS_DN<3>
  VSS18  = GND
  DQ28_A  = M_H_CPU0_SA_DQ<28>
  VSS19  = GND
  DQ29_A  = M_H_CPU0_SA_DQ<29>
  VSS20  = GND
  CB0_A  = M_H_CPU0_SA_CB<0>
  VSS21  = GND
  CB1_A  = M_H_CPU0_SA_CB<1>
  VSS22  = GND
  DQS4_A_T  = M_H_CPU0_SA_DQS_DP<4>
  DQS4_A_C  = M_H_CPU0_SA_DQS_DN<4>
  VSS23  = GND
  CB4_A  = M_H_CPU0_SA_CB<4>
  VSS24  = GND
  CB5_A  = M_H_CPU0_SA_CB<5>
  VSS25  = GND
  ALERT_N  = M_H_CPU0_ALERT_N
  VSS26  = GND
  CS0_A_N  = M_H_CPU0_SA_CS_N<2>
  VSS27  = GND
  CA0_A  = M_H_CPU0_SA_CA<0>
  VSS28  = GND
  CA2_A  = M_H_CPU0_SA_CA<2>
  VSS29  = GND
  CA4_A  = M_H_CPU0_SA_CA<4>
  VSS30  = GND
  CA6_A  = M_H_CPU0_SA_CA<6>
  VSS31  = GND
  PAR_A  = M_H_CPU0_SA_PAR
  VSS32  = GND
  CA0_B  = M_H_CPU0_SB_CA<0>
  VSS33  = GND
  CA2_B  = M_H_CPU0_SB_CA<2>
  VSS34  = GND
  CA4_B  = M_H_CPU0_SB_CA<4>
  VSS35  = GND
  CA6_B  = M_H_CPU0_SB_CA<6>
  VSS36  = GND
  CS0_B_N  = M_H_CPU0_SB_CS_N<2>
  VSS37  = GND
  \lbd||rsp_a_n\  = M_H_CPU0_SA_RSP<1>
  \lbs||rsp_b_n\  = M_H_CPU0_SB_RSP<1>
  VSS38  = GND
  CB4_B  = M_H_CPU0_SB_CB<4>
  VSS39  = GND
  CB5_B  = M_H_CPU0_SB_CB<5>
  VSS40  = GND
  \dqs9_b_t||tdqs9_b_t||dbi4_b_n\  = M_H_CPU0_SB_DQS_DP<9>
  \dqs9_b_c||tdqs9_b_c\  = M_H_CPU0_SB_DQS_DN<9>
  VSS41  = GND
  CB0_B  = M_H_CPU0_SB_CB<0>
  VSS42  = GND
  CB1_B  = M_H_CPU0_SB_CB<1>
  VSS43  = GND
  DQ0_B  = M_H_CPU0_SB_DQ<0>
  VSS44  = GND
  DQ1_B  = M_H_CPU0_SB_DQ<1>
  VSS45  = GND
  DQS0_B_T  = M_H_CPU0_SB_DQS_DP<0>
  DQS0_B_C  = M_H_CPU0_SB_DQS_DN<0>
  VSS46  = GND
  DQ4_B  = M_H_CPU0_SB_DQ<4>
  VSS47  = GND
  DQ5_B  = M_H_CPU0_SB_DQ<5>
  VSS48  = GND
  DQ8_B  = M_H_CPU0_SB_DQ<8>
  VSS49  = GND
  DQ9_B  = M_H_CPU0_SB_DQ<9>
  VSS50  = GND
  DQS1_B_T  = M_H_CPU0_SB_DQS_DP<1>
  DQS1_B_C  = M_H_CPU0_SB_DQS_DN<1>
  VSS51  = GND
  DQ12_B  = M_H_CPU0_SB_DQ<12>
  VSS52  = GND
  DQ13_B  = M_H_CPU0_SB_DQ<13>
  VSS53  = GND
  DQ16_B  = M_H_CPU0_SB_DQ<16>
  VSS54  = GND
  DQ17_B  = M_H_CPU0_SB_DQ<17>
  VSS55  = GND
  DQS2_B_T  = M_H_CPU0_SB_DQS_DP<2>
  DQS2_B_C  = M_H_CPU0_SB_DQS_DN<2>
  VSS56  = GND
  DQ20_B  = M_H_CPU0_SB_DQ<20>
  VSS57  = GND
  DQ21_B  = M_H_CPU0_SB_DQ<21>
  VSS58  = GND
  DQ24_B  = M_H_CPU0_SB_DQ<24>
  VSS59  = GND
  DQ25_B  = M_H_CPU0_SB_DQ<25>
  VSS60  = GND
  DQS3_B_T  = M_H_CPU0_SB_DQS_DP<3>
  DQS3_B_C  = M_H_CPU0_SB_DQS_DN<3>
  VSS61  = GND
  DQ28_B  = M_H_CPU0_SB_DQ<28>
  VSS62  = GND
  DQ29_B  = M_H_CPU0_SB_DQ<29>
  VSS63  = GND
  RFU1  = TP_CHH_CPU0_DIMM2_FRU_1
  VIN_BULK1  = P12V_S3_AUX_CPU0_NVDIMM
  VIN_BULK2  = P12V_S3_AUX_CPU0_NVDIMM
  \pwr_good||fail_n\  = PWRGD_CHH_CPU0_DIMM2
  HSA  = PD_CHH_CPU0_DIMM2_SAA
  RFU2  = TP_CHH_CPU0_DIMM2_FRU_2
  RFU3  = TP_CHH_CPU0_DIMM2_FRU_3
  VSS64  = GND
  DQ2_A  = M_H_CPU0_SA_DQ<2>
  VSS65  = GND
  DQ3_A  = M_H_CPU0_SA_DQ<3>
  VSS66  = GND
  \dqs5_a_c||tdqs5_a_c||dqs5_a_t||tdqs5_a_t\  = M_H_CPU0_SA_DQS_DN<5>
  \dqs5_a_t||tdqs5_a_t\  = M_H_CPU0_SA_DQS_DP<5>
  VSS67  = GND
  DQ6_A  = M_H_CPU0_SA_DQ<6>
  VSS68  = GND
  DQ7_A  = M_H_CPU0_SA_DQ<7>
  VSS69  = GND
  DQ10_A  = M_H_CPU0_SA_DQ<10>
  VSS70  = GND
  DQ11_A  = M_H_CPU0_SA_DQ<11>
  VSS71  = GND
  \dqs6_a_c||tdqs6_a_c||dqs6_a_t||tdqs6_a_t\  = M_H_CPU0_SA_DQS_DN<6>
  \dqs6_a_t||tdqs6_a_t\  = M_H_CPU0_SA_DQS_DP<6>
  VSS72  = GND
  DQ14_A  = M_H_CPU0_SA_DQ<14>
  VSS73  = GND
  DQ15_A  = M_H_CPU0_SA_DQ<15>
  VSS74  = GND
  DQ18_A  = M_H_CPU0_SA_DQ<18>
  VSS75  = GND
  DQ19_A  = M_H_CPU0_SA_DQ<19>
  VSS76  = GND
  \dqs7_a_c||tdqs7_a_c\  = M_H_CPU0_SA_DQS_DN<7>
  \dqs7_a_t||tdqs7_a_t\  = M_H_CPU0_SA_DQS_DP<7>
  VSS77  = GND
  DQ22_A  = M_H_CPU0_SA_DQ<22>
  VSS78  = GND
  DQ23_A  = M_H_CPU0_SA_DQ<23>
  VSS79  = GND
  DQ26_A  = M_H_CPU0_SA_DQ<26>
  VSS80  = GND
  DQ27_A  = M_H_CPU0_SA_DQ<27>
  VSS81  = GND
  \dqs8_a_c||tdqs8_a_c\  = M_H_CPU0_SA_DQS_DN<8>
  \dqs8_a_t||tdqs8_a_t\  = M_H_CPU0_SA_DQS_DP<8>
  VSS82  = GND
  DQ30_A  = M_H_CPU0_SA_DQ<30>
  VSS83  = GND
  DQ31_A  = M_H_CPU0_SA_DQ<31>
  VSS84  = GND
  CB2_A  = M_H_CPU0_SA_CB<2>
  VSS85  = GND
  CB3_A  = M_H_CPU0_SA_CB<3>
  VSS86  = GND
  \dqs9_a_c||tdqs9_a_c\  = M_H_CPU0_SA_DQS_DN<9>
  \dqs9_a_t||tdqs9_a_t\  = M_H_CPU0_SA_DQS_DP<9>
  VSS87  = GND
  CB6_A  = M_H_CPU0_SA_CB<6>
  VSS88  = GND
  CB7_A  = M_H_CPU0_SA_CB<7>
  VSS89  = GND
  RESET_N  = RST_M_GH_CPU0_FPGA_N
  VSS90  = GND
  CS1_A_N  = M_H_CPU0_SA_CS_N<3>
  VSS91  = GND
  CA1_A  = M_H_CPU0_SA_CA<1>
  VSS92  = GND
  CA3_A  = M_H_CPU0_SA_CA<3>
  VSS93  = GND
  CA5_A  = M_H_CPU0_SA_CA<5>
  VSS94  = GND
  CK_T  = M_H_CPU0_CLK_DP<1>
  CK_C  = M_H_CPU0_CLK_DN<1>
  VSS95  = GND
  RFU4  = TP_CHH_CPU0_DIMM2_FRU_4
  CA1_B  = M_H_CPU0_SB_CA<1>
  VSS96  = GND
  CA3_B  = M_H_CPU0_SB_CA<3>
  VSS97  = GND
  CA5_B  = M_H_CPU0_SB_CA<5>
  VSS98  = GND
  PAR_B  = M_H_CPU0_SB_PAR
  VSS99  = GND
  CS1_B_N  = M_H_CPU0_SB_CS_N<3>
  VSS100  = GND
  RFU5  = TP_CHH_CPU0_DIMM2_FRU_5
  RFU6  = TP_CHH_CPU0_DIMM2_FRU_6
  VSS101  = GND
  CB6_B  = M_H_CPU0_SB_CB<6>
  VSS102  = GND
  CB7_B  = M_H_CPU0_SB_CB<7>
  VSS103  = GND
  DQS4_B_C  = M_H_CPU0_SB_DQS_DN<4>
  DQS4_B_T  = M_H_CPU0_SB_DQS_DP<4>
  VSS104  = GND
  CB2_B  = M_H_CPU0_SB_CB<2>
  VSS105  = GND
  CB3_B  = M_H_CPU0_SB_CB<3>
  VSS106  = GND
  DQ2_B  = M_H_CPU0_SB_DQ<2>
  VSS107  = GND
  DQ3_B  = M_H_CPU0_SB_DQ<3>
  VSS108  = GND
  \dqs5_b_c||tdqs5_b_c\  = M_H_CPU0_SB_DQS_DN<5>
  \dqs5_b_t||tdqs5_b_t\  = M_H_CPU0_SB_DQS_DP<5>
  VSS109  = GND
  DQ6_B  = M_H_CPU0_SB_DQ<6>
  VSS110  = GND
  DQ7_B  = M_H_CPU0_SB_DQ<7>
  VSS111  = GND
  DQ10_B  = M_H_CPU0_SB_DQ<10>
  VSS112  = GND
  DQ11_B  = M_H_CPU0_SB_DQ<11>
  VSS113  = GND
  \dqs6_b_c||tdqs6_b_c\  = M_H_CPU0_SB_DQS_DN<6>
  \dqs6_b_t||tdqs6_b_t\  = M_H_CPU0_SB_DQS_DP<6>
  VSS114  = GND
  DQ14_B  = M_H_CPU0_SB_DQ<14>
  VSS115  = GND
  DQ15_B  = M_H_CPU0_SB_DQ<15>
  VSS116  = GND
  DQ18_B  = M_H_CPU0_SB_DQ<18>
  VSS117  = GND
  DQ19_B  = M_H_CPU0_SB_DQ<19>
  VSS118  = GND
  \dqs7_b_c||tdqs7_b_c\  = M_H_CPU0_SB_DQS_DN<7>
  \dqs7_b_t||tdqs7_b_t\  = M_H_CPU0_SB_DQS_DP<7>
  VSS119  = GND
  DQ22_B  = M_H_CPU0_SB_DQ<22>
  VSS120  = GND
  DQ23_B  = M_H_CPU0_SB_DQ<23>
  VSS121  = GND
  DQ26_B  = M_H_CPU0_SB_DQ<26>
  VSS122  = GND
  DQ27_B  = M_H_CPU0_SB_DQ<27>
  VSS123  = GND
  \dqs8_b_c||tdqs8_b_c\  = M_H_CPU0_SB_DQS_DN<8>
  \dqs8_b_t||tdqs8_b_t\  = M_H_CPU0_SB_DQS_DP<8>
  VSS124  = GND
  DQ30_B  = M_H_CPU0_SB_DQ<30>
  VSS125  = GND
  DQ31_B  = M_H_CPU0_SB_DQ<31>
  VSS126  = GND
  G1  = GND
  G2  = GND
  G3  = GND

(kicad_pcb
	(version 20260206)
	(generator "pcbnew")
	(generator_version "10.0")
	(general
		(thickness 1.6)
		(legacy_teardrops no)
	)
	(paper "A4")
	(title_block
		(title "03242023_DA0F0TMBIJ0_F0T_Motherboard_J_brd_V01_OCP.brd")
		(comment 1 "Grand Teton / footprint 1690 of 6105 (J16), pads 275-291 of 291")
	)
	(layers
		(0 "F.Cu" signal "TOP")
		(4 "In1.Cu" signal "GND")
		(6 "In2.Cu" signal "IN1")
		(8 "In3.Cu" signal "GND1")
		(10 "In4.Cu" signal "IN2")
		(12 "In5.Cu" signal "GND2")
		(14 "In6.Cu" signal "IN3")
		(16 "In7.Cu" signal "GND3")
		(18 "In8.Cu" signal "VCC")
		(20 "In9.Cu" signal "VCC1")
		(22 "In10.Cu" signal "GND4")
		(24 "In11.Cu" signal "IN4")
		(26 "In12.Cu" signal "GND5")
		(28 "In13.Cu" signal "IN5")
		(30 "In14.Cu" signal "GND6")
		(32 "In15.Cu" signal "IN6")
		(34 "In16.Cu" signal "GND7")
		(2 "B.Cu" signal "BOTTOM")
		(9 "F.Adhes" user "F.Adhesive")
		(11 "B.Adhes" user "B.Adhesive")
		(13 "F.Paste" user "Package Geometry/Pastemask Top")
		(15 "B.Paste" user "Package Geometry/Pastemask Bottom")
		(5 "F.SilkS" user "Ref Des/Silkscreen Top")
		(7 "B.SilkS" user "Ref Des/Silkscreen Bottom")
		(1 "F.Mask" user "Board Geometry/Soldermask Top")
		(3 "B.Mask" user "Board Geometry/Soldermask Bottom")
		(17 "Dwgs.User" user "User.Drawings")
		(19 "Cmts.User" user "User.Comments")
		(21 "Eco1.User" user "User.Eco1")
		(23 "Eco2.User" user "User.Eco2")
		(25 "Edge.Cuts" user "Board Geometry/Outline")
		(27 "Margin" user)
		(31 "F.CrtYd" user "Package Geometry/Place Bound Top")
		(29 "B.CrtYd" user "Package Geometry/Place Bound Bottom")
		(35 "F.Fab" user "Ref Des/Assembly Top")
		(33 "B.Fab" user "Ref Des/Assembly Bottom")
	)
	(footprint ""
		(layer "F.Cu")
		(at 454.066148 -258.091686)
		(property "Reference" "J16"
			(at -0.279908 -81.779872 0)
			(unlocked yes)
			(layer "F.SilkS")
			(effects
				(font
					(size 0.7874 0.5842)
					(thickness 0.1524)
				)
				(justify left)
			)
		)
		(property "Value" ""
			(at 0 0 0)
			(layer "F.Fab")
			(effects
				(font
					(size 1.27 1.27)
				)
			)
		)
		(duplicate_pad_numbers_are_jumpers no)
		(pad "275" smd rect
			(at 2.050034 52.274978 270)
			(size 0.519938 1.4986)
			(layers "F.Cu" "F.Mask" "F.Paste")
			(net "GND")
		)
		(pad "276" smd rect
			(at 2.050034 53.125116 270)
			(size 0.519938 1.4986)
			(layers "F.Cu" "F.Mask" "F.Paste")
			(net "M_H_CPU0_SB_DQ<23>")
		)
		(pad "277" smd rect
			(at 2.050034 53.975 270)
			(size 0.519938 1.4986)
			(layers "F.Cu" "F.Mask" "F.Paste")
			(net "GND")
		)
		(pad "278" smd rect
			(at 2.050034 54.824884 270)
			(size 0.519938 1.4986)
			(layers "F.Cu" "F.Mask" "F.Paste")
			(net "M_H_CPU0_SB_DQ<26>")
		)
		(pad "279" smd rect
			(at 2.050034 55.675022 270)
			(size 0.519938 1.4986)
			(layers "F.Cu" "F.Mask" "F.Paste")
			(net "GND")
		)
		(pad "280" smd rect
			(at 2.050034 56.524906 270)
			(size 0.519938 1.4986)
			(layers "F.Cu" "F.Mask" "F.Paste")
			(net "M_H_CPU0_SB_DQ<27>")
		)
		(pad "281" smd rect
			(at 2.050034 57.375044 270)
			(size 0.519938 1.4986)
			(layers "F.Cu" "F.Mask" "F.Paste")
			(net "GND")
		)
		(pad "282" smd rect
			(at 2.050034 58.224928 270)
			(size 0.519938 1.4986)
			(layers "F.Cu" "F.Mask" "F.Paste")
			(net "M_H_CPU0_SB_DQS_DN<8>")
		)
		(pad "283" smd rect
			(at 2.050034 59.075066 270)
			(size 0.519938 1.4986)
			(layers "F.Cu" "F.Mask" "F.Paste")
			(net "M_H_CPU0_SB_DQS_DP<8>")
		)
		(pad "284" smd rect
			(at 2.050034 59.92495 270)
			(size 0.519938 1.4986)
			(layers "F.Cu" "F.Mask" "F.Paste")
			(net "GND")
		)
		(pad "285" smd rect
			(at 2.050034 60.775088 270)
			(size 0.519938 1.4986)
			(layers "F.Cu" "F.Mask" "F.Paste")
			(net "M_H_CPU0_SB_DQ<30>")
		)
		(pad "286" smd rect
			(at 2.050034 61.624972 270)
			(size 0.519938 1.4986)
			(layers "F.Cu" "F.Mask" "F.Paste")
			(net "GND")
		)
		(pad "287" smd rect
			(at 2.050034 62.47511 270)
			(size 0.519938 1.4986)
			(layers "F.Cu" "F.Mask" "F.Paste")
			(net "M_H_CPU0_SB_DQ<31>")
		)
		(pad "288" smd rect
			(at 2.050034 63.324994 270)
			(size 0.519938 1.4986)
			(layers "F.Cu" "F.Mask" "F.Paste")
			(net "GND")
		)
		(pad "G1" thru_hole oval
			(at 0 -68.97497)
			(size 2.8194 1.5748)
			(drill oval 2.4384 1.1938)
			(layers "*.Cu" "*.Mask")
			(remove_unused_layers no)
			(net "GND")
			(clearance 0.127)
			(thermal_gap 0.127)
		)
		(pad "G2" thru_hole oval
			(at 0 3.875024)
			(size 2.8194 1.5748)
			(drill oval 2.4384 1.1938)
			(layers "*.Cu" "*.Mask")
			(remove_unused_layers no)
			(net "GND")
			(clearance 0.127)
			(thermal_gap 0.127)
		)
		(pad "G3" thru_hole oval
			(at 0 68.97497)
			(size 2.8194 1.5748)
			(drill oval 2.4384 1.1938)
			(layers "*.Cu" "*.Mask")
			(remove_unused_layers no)
			(net "GND")
			(clearance 0.127)
			(thermal_gap 0.127)
		)
	)
)
